(kicad_pcb
	(version 20241229)
	(generator "pcbnew")
	(generator_version "9.0")
	(general
		(thickness 1.294)
		(legacy_teardrops no)
	)
	(paper "A3")
	(title_block
		(title "Kintex 410T devboard")
		(date "2024-04-03")
		(rev "1.1.2")
		(comment 9 "footprints 916-921 of 975")
	)
	(layers
		(0 "F.Cu" mixed)
		(4 "In1.Cu" power)
		(6 "In2.Cu" power)
		(8 "In3.Cu" mixed)
		(10 "In4.Cu" power)
		(12 "In5.Cu" mixed)
		(14 "In6.Cu" power)
		(16 "In7.Cu" mixed)
		(18 "In8.Cu" power)
		(2 "B.Cu" mixed)
		(9 "F.Adhes" user "F.Adhesive")
		(11 "B.Adhes" user "B.Adhesive")
		(13 "F.Paste" user)
		(15 "B.Paste" user)
		(5 "F.SilkS" user "F.Silkscreen")
		(7 "B.SilkS" user "B.Silkscreen")
		(1 "F.Mask" user)
		(3 "B.Mask" user)
		(17 "Dwgs.User" user "User.Drawings")
		(19 "Cmts.User" user "User.Comments")
		(21 "Eco1.User" user "User.Eco1")
		(23 "Eco2.User" user "User.Eco2")
		(25 "Edge.Cuts" user)
		(27 "Margin" user)
		(31 "F.CrtYd" user "F.Courtyard")
		(29 "B.CrtYd" user "B.Courtyard")
		(35 "F.Fab" user)
		(33 "B.Fab" user)
	)
	(footprint "antmicro-footprints:R_Array_4x0201_Panasonic_EXB18V"
		(layer "B.Cu")
		(at 164.199999 144.999999)
		(property "Reference" "R13"
			(at -4.524999 6.250001 0)
			(layer "B.SilkS")
			(effects
				(font
					(size 0.7 0.7)
					(thickness 0.15)
				)
				(justify left bottom mirror)
			)
		)
		(property "Value" "4x39R_0201_array"
			(at -1.1 -1.8 0)
			(layer "B.Fab")
			(effects
				(font
					(size 0.7 0.7)
					(thickness 0.15)
				)
				(justify right bottom mirror)
			)
		)
		(property "Description" "Fixed Network Resistor, 39 ohm, Isolated, 4 Resistors, 0502 [1406 Metric], Flat, ± 5%"
			(at 0 0 0)
			(layer "F.Fab")
			(hide yes)
			(effects
				(font
					(size 1.27 1.27)
					(thickness 0.15)
				)
			)
		)
		(property "Author" "Antmicro"
			(at 0 0 0)
			(layer "B.Fab")
			(hide yes)
			(effects
				(font
					(size 1 1)
					(thickness 0.15)
				)
				(justify mirror)
			)
		)
		(property "License" "Apache-2.0"
			(at 0 0 0)
			(layer "B.Fab")
			(hide yes)
			(effects
				(font
					(size 1 1)
					(thickness 0.15)
				)
				(justify mirror)
			)
		)
		(property "MPN" "EXB-18V390JX"
			(at 0 0 0)
			(layer "B.Fab")
			(hide yes)
			(effects
				(font
					(size 1 1)
					(thickness 0.15)
				)
				(justify mirror)
			)
		)
		(property "Manufacturer" "Panasonic"
			(at 0 0 0)
			(layer "B.Fab")
			(hide yes)
			(effects
				(font
					(size 1 1)
					(thickness 0.15)
				)
				(justify mirror)
			)
		)
		(property "Val" "4x39R_0201"
			(at 0 0 0)
			(layer "B.Fab")
			(hide yes)
			(effects
				(font
					(size 1 1)
					(thickness 0.15)
				)
				(justify mirror)
			)
		)
		(sheetname "DRAM + SRAM")
		(sheetfile "ram.kicad_sch")
		(attr smd)
		(fp_line
			(start -0.8 0.45)
			(end -0.8 -0.45)
			(stroke
				(width 0.12)
				(type solid)
			)
			(layer "B.SilkS")
		)
		(fp_line
			(start 0.8 0.45)
			(end 0.8 -0.45)
			(stroke
				(width 0.12)
				(type solid)
			)
			(layer "B.SilkS")
		)
		(fp_rect
			(start -0.898 0.66)
			(end 0.898 -0.65)
			(stroke
				(width 0.05)
				(type solid)
			)
			(fill no)
			(layer "B.CrtYd")
		)
		(pad "1" smd roundrect
			(at -0.6 -0.298)
			(size 0.2 0.4)
			(layers "B.Cu" "B.Mask" "B.Paste")
			(roundrect_rratio 0.25)
			(net 544 "/DRAM + SRAM/DDR.A13")
			(pinfunction "R1.1")
			(pintype "passive")
		)
		(pad "2" smd roundrect
			(at -0.202 -0.298)
			(size 0.2 0.4)
			(layers "B.Cu" "B.Mask" "B.Paste")
			(roundrect_rratio 0.25)
			(net 538 "/DRAM + SRAM/DDR.A7")
			(pinfunction "R2.1")
			(pintype "passive")
		)
		(pad "3" smd roundrect
			(at 0.2 -0.298)
			(size 0.2 0.4)
			(layers "B.Cu" "B.Mask" "B.Paste")
			(roundrect_rratio 0.25)
			(net 540 "/DRAM + SRAM/DDR.A9")
			(pinfunction "R3.1")
			(pintype "passive")
		)
		(pad "4" smd roundrect
			(at 0.598 -0.298)
			(size 0.2 0.4)
			(layers "B.Cu" "B.Mask" "B.Paste")
			(roundrect_rratio 0.25)
			(net 536 "/DRAM + SRAM/DDR.A5")
			(pinfunction "R4.1")
			(pintype "passive")
		)
		(pad "5" smd roundrect
			(at 0.598 0.3)
			(size 0.2 0.4)
			(layers "B.Cu" "B.Mask" "B.Paste")
			(roundrect_rratio 0.25)
			(net 7 "+0V675_VTT")
			(pinfunction "R4.2")
			(pintype "passive")
		)
		(pad "6" smd roundrect
			(at 0.2 0.3)
			(size 0.2 0.4)
			(layers "B.Cu" "B.Mask" "B.Paste")
			(roundrect_rratio 0.25)
			(net 7 "+0V675_VTT")
			(pinfunction "R3.2")
			(pintype "passive")
		)
		(pad "7" smd roundrect
			(at -0.202 0.3)
			(size 0.2 0.4)
			(layers "B.Cu" "B.Mask" "B.Paste")
			(roundrect_rratio 0.25)
			(net 7 "+0V675_VTT")
			(pinfunction "R2.2")
			(pintype "passive")
		)
		(pad "8" smd roundrect
			(at -0.6 0.3)
			(size 0.2 0.4)
			(layers "B.Cu" "B.Mask" "B.Paste")
			(roundrect_rratio 0.25)
			(net 7 "+0V675_VTT")
			(pinfunction "R1.2")
			(pintype "passive")
		)
	)
	(footprint "antmicro-footprints:C_0603_1608Metric"
		(layer "B.Cu")
		(at 200 134 90)
		(descr "Capacitor SMD 0603")
		(tags "capacitor 0603")
		(property "Reference" "C385"
			(at 27.7 25.75 90)
			(layer "B.SilkS")
			(effects
				(font
					(size 0.7 0.7)
					(thickness 0.15)
				)
				(justify right bottom mirror)
			)
		)
		(property "Value" "C_47u_0603"
			(at 0 -1.6 90)
			(layer "B.Fab")
			(effects
				(font
					(size 0.7 0.7)
					(thickness 0.15)
				)
				(justify right bottom mirror)
			)
		)
		(property "Description" "SMD Multilayer Ceramic Capacitor, 47 µF, 6.3 V, 0603 [1608 Metric], ± 20%, X5R, GRM Series"
			(at 0 0 90)
			(layer "F.Fab")
			(hide yes)
			(effects
				(font
					(size 1.27 1.27)
					(thickness 0.15)
				)
			)
		)
		(property "Author" "Antmicro"
			(at 334 -66 0)
			(layer "B.Fab")
			(hide yes)
			(effects
				(font
					(size 1 1)
					(thickness 0.15)
				)
				(justify mirror)
			)
		)
		(property "Dielectric" ""
			(at 334 -66 0)
			(layer "B.Fab")
			(hide yes)
			(effects
				(font
					(size 1 1)
					(thickness 0.15)
				)
				(justify mirror)
			)
		)
		(property "License" "Apache-2.0"
			(at 334 -66 0)
			(layer "B.Fab")
			(hide yes)
			(effects
				(font
					(size 1 1)
					(thickness 0.15)
				)
				(justify mirror)
			)
		)
		(property "MPN" "GRM188R60J476ME15D"
			(at 334 -66 0)
			(layer "B.Fab")
			(hide yes)
			(effects
				(font
					(size 1 1)
					(thickness 0.15)
				)
				(justify mirror)
			)
		)
		(property "Manufacturer" "Murata"
			(at 334 -66 0)
			(layer "B.Fab")
			(hide yes)
			(effects
				(font
					(size 1 1)
					(thickness 0.15)
				)
				(justify mirror)
			)
		)
		(property "Val" "47u"
			(at 334 -66 0)
			(layer "B.Fab")
			(hide yes)
			(effects
				(font
					(size 1 1)
					(thickness 0.15)
				)
				(justify mirror)
			)
		)
		(property "Voltage" ""
			(at 334 -66 0)
			(layer "B.Fab")
			(hide yes)
			(effects
				(font
					(size 1 1)
					(thickness 0.15)
				)
				(justify mirror)
			)
		)
		(sheetname "FPGA supply")
		(sheetfile "fpga-supply.kicad_sch")
		(attr smd)
		(fp_line
			(start -0.15 -0.4)
			(end 0.15 -0.4)
			(stroke
				(width 0.15)
				(type solid)
			)
			(layer "B.SilkS")
		)
		(fp_line
			(start -0.15 0.4)
			(end 0.15 0.4)
			(stroke
				(width 0.15)
				(type solid)
			)
			(layer "B.SilkS")
		)
		(fp_rect
			(start -1.25 0.65)
			(end 1.25 -0.65)
			(stroke
				(width 0.05)
				(type solid)
			)
			(fill no)
			(layer "B.CrtYd")
		)
		(fp_rect
			(start -0.8 0.4)
			(end 0.8 -0.4)
			(stroke
				(width 0.15)
				(type solid)
			)
			(fill no)
			(layer "B.Fab")
		)
		(pad "1" smd roundrect
			(at -0.7 0 90)
			(size 0.8 1)
			(layers "B.Cu" "B.Mask" "B.Paste")
			(roundrect_rratio 0.2)
			(net 1 "GND")
			(pintype "passive")
		)
		(pad "2" smd roundrect
			(at 0.7 0 90)
			(size 0.8 1)
			(layers "B.Cu" "B.Mask" "B.Paste")
			(roundrect_rratio 0.2)
			(net 650 "+1V0")
			(pintype "passive")
		)
	)
	(footprint "antmicro-footprints:C_0402_1005Metric"
		(layer "B.Cu")
		(at 208 135.5 180)
		(descr "Capacitor SMD 0402")
		(tags "capacitor SMD 0402")
		(property "Reference" "C40"
			(at -1.1 0.425 0)
			(layer "B.SilkS")
			(effects
				(font
					(size 0.7 0.7)
					(thickness 0.15)
				)
				(justify left bottom mirror)
			)
		)
		(property "Value" "C_100n_0402"
			(at 0 -1.169 0)
			(layer "B.Fab")
			(effects
				(font
					(size 0.7 0.7)
					(thickness 0.15)
				)
				(justify left bottom mirror)
			)
		)
		(property "Description" "SMD Multilayer Ceramic Capacitor, 0.1 µF, 50 V, 0402 [1005 Metric], ± 10%, X5R, GRM Series"
			(at 0 0 180)
			(layer "F.Fab")
			(hide yes)
			(effects
				(font
					(size 1.27 1.27)
					(thickness 0.15)
				)
			)
		)
		(property "Author" "Antmicro"
			(at 416 271 0)
			(layer "B.Fab")
			(hide yes)
			(effects
				(font
					(size 1 1)
					(thickness 0.15)
				)
				(justify mirror)
			)
		)
		(property "Dielectric" "X5R"
			(at 416 271 0)
			(layer "B.Fab")
			(hide yes)
			(effects
				(font
					(size 1 1)
					(thickness 0.15)
				)
				(justify mirror)
			)
		)
		(property "License" "Apache-2.0"
			(at 416 271 0)
			(layer "B.Fab")
			(hide yes)
			(effects
				(font
					(size 1 1)
					(thickness 0.15)
				)
				(justify mirror)
			)
		)
		(property "MPN" "GRM155R61H104KE14D"
			(at 416 271 0)
			(layer "B.Fab")
			(hide yes)
			(effects
				(font
					(size 1 1)
					(thickness 0.15)
				)
				(justify mirror)
			)
		)
		(property "Manufacturer" "Murata"
			(at 416 271 0)
			(layer "B.Fab")
			(hide yes)
			(effects
				(font
					(size 1 1)
					(thickness 0.15)
				)
				(justify mirror)
			)
		)
		(property "Val" "100n"
			(at 416 271 0)
			(layer "B.Fab")
			(hide yes)
			(effects
				(font
					(size 1 1)
					(thickness 0.15)
				)
				(justify mirror)
			)
		)
		(property "Voltage" "50V"
			(at 416 271 0)
			(layer "B.Fab")
			(hide yes)
			(effects
				(font
					(size 1 1)
					(thickness 0.15)
				)
				(justify mirror)
			)
		)
		(sheetname "FPGA Bank 12 & 13")
		(sheetfile "fpga-bank-12-13.kicad_sch")
		(attr smd)
		(fp_rect
			(start -0.925 0.47)
			(end 0.925 -0.47)
			(stroke
				(width 0.05)
				(type default)
			)
			(fill no)
			(layer "B.CrtYd")
		)
		(fp_line
			(start 0.504 0.25)
			(end 0.504 -0.248)
			(stroke
				(width 0.15)
				(type solid)
			)
			(layer "B.Fab")
		)
		(fp_line
			(start 0.504 -0.248)
			(end -0.494 -0.248)
			(stroke
				(width 0.15)
				(type solid)
			)
			(layer "B.Fab")
		)
		(fp_line
			(start -0.494 0.25)
			(end 0.504 0.25)
			(stroke
				(width 0.15)
				(type solid)
			)
			(layer "B.Fab")
		)
		(fp_line
			(start -0.494 -0.248)
			(end -0.494 0.25)
			(stroke
				(width 0.15)
				(type solid)
			)
			(layer "B.Fab")
		)
		(pad "1" smd roundrect
			(at -0.48 0 180)
			(size 0.59 0.64)
			(layers "B.Cu" "B.Mask" "B.Paste")
			(roundrect_rratio 0.25)
			(net 1 "GND")
			(pintype "passive")
		)
		(pad "2" smd roundrect
			(at 0.48 0 180)
			(size 0.59 0.64)
			(layers "B.Cu" "B.Mask" "B.Paste")
			(roundrect_rratio 0.25)
			(net 24 "+3V3")
			(pintype "passive")
		)
	)
	(footprint "antmicro-footprints:R_0402_1005Metric"
		(layer "B.Cu")
		(at 242.351 143.05 -90)
		(descr "Resistor SMD 0402")
		(tags "resistor SMD 0402")
		(property "Reference" "R165"
			(at 0.85 -0.399 90)
			(layer "B.SilkS")
			(effects
				(font
					(size 0.7 0.7)
					(thickness 0.15)
				)
				(justify left bottom mirror)
			)
		)
		(property "Value" "R_0R_0402"
			(at 0 -1.4 90)
			(layer "B.Fab")
			(effects
				(font
					(size 0.7 0.7)
					(thickness 0.15)
				)
				(justify left bottom mirror)
			)
		)
		(property "Description" "SMD Chip Resistor, Jumper, 0 ohm, 100 mW, 0402 [1005 Metric], Thick Film, General Purpose"
			(at 0 0 270)
			(layer "F.Fab")
			(hide yes)
			(effects
				(font
					(size 1.27 1.27)
					(thickness 0.15)
				)
			)
		)
		(property "Author" "Antmicro"
			(at 99.301 385.401 0)
			(layer "B.Fab")
			(hide yes)
			(effects
				(font
					(size 1 1)
					(thickness 0.15)
				)
				(justify mirror)
			)
		)
		(property "Current" "1A"
			(at 99.301 385.401 0)
			(layer "B.Fab")
			(hide yes)
			(effects
				(font
					(size 1 1)
					(thickness 0.15)
				)
				(justify mirror)
			)
		)
		(property "License" "Apache-2.0"
			(at 99.301 385.401 0)
			(layer "B.Fab")
			(hide yes)
			(effects
				(font
					(size 1 1)
					(thickness 0.15)
				)
				(justify mirror)
			)
		)
		(property "MPN" "ERJ2GE0R00X"
			(at 99.301 385.401 0)
			(layer "B.Fab")
			(hide yes)
			(effects
				(font
					(size 1 1)
					(thickness 0.15)
				)
				(justify mirror)
			)
		)
		(property "Manufacturer" "Panasonic"
			(at 99.301 385.401 0)
			(layer "B.Fab")
			(hide yes)
			(effects
				(font
					(size 1 1)
					(thickness 0.15)
				)
				(justify mirror)
			)
		)
		(property "Tolerance" ""
			(at 99.301 385.401 0)
			(layer "B.Fab")
			(hide yes)
			(effects
				(font
					(size 1 1)
					(thickness 0.15)
				)
				(justify mirror)
			)
		)
		(property "Val" "0R"
			(at 99.301 385.401 0)
			(layer "B.Fab")
			(hide yes)
			(effects
				(font
					(size 1 1)
					(thickness 0.15)
				)
				(justify mirror)
			)
		)
		(sheetname "USB PHY")
		(sheetfile "usb-phy.kicad_sch")
		(attr smd)
		(fp_rect
			(start -0.925 0.47)
			(end 0.925 -0.47)
			(stroke
				(width 0.05)
				(type default)
			)
			(fill no)
			(layer "B.CrtYd")
		)
		(fp_rect
			(start -0.5 0.25)
			(end 0.5 -0.25)
			(stroke
				(width 0.15)
				(type solid)
			)
			(fill no)
			(layer "B.Fab")
		)
		(pad "1" smd roundrect
			(at -0.48 0 270)
			(size 0.59 0.64)
			(layers "B.Cu" "B.Mask" "B.Paste")
			(roundrect_rratio 0.25)
			(net 343 "Net-(Q17-G)")
			(pintype "passive")
		)
		(pad "2" smd roundrect
			(at 0.48 0 270)
			(size 0.59 0.64)
			(layers "B.Cu" "B.Mask" "B.Paste")
			(roundrect_rratio 0.25)
			(net 925 "/USB PHY/BDBUS3")
			(pintype "passive")
		)
	)
	(footprint "antmicro-footprints:R_0402_1005Metric"
		(layer "B.Cu")
		(at 261.5 91)
		(descr "Resistor SMD 0402")
		(tags "resistor SMD 0402")
		(property "Reference" "R110"
			(at 1.375 1.275 180)
			(layer "B.SilkS")
			(effects
				(font
					(size 0.7 0.7)
					(thickness 0.15)
				)
				(justify left bottom mirror)
			)
		)
		(property "Value" "R_1k_0402"
			(at 0 -1.4 180)
			(layer "B.Fab")
			(effects
				(font
					(size 0.7 0.7)
					(thickness 0.15)
				)
				(justify left bottom mirror)
			)
		)
		(property "Description" "SMD Chip Resistor, 1 kohm, ± 1%, 63 mW, 0402 [1005 Metric], Thick Film, General Purpose"
			(at 0 0 0)
			(layer "F.Fab")
			(hide yes)
			(effects
				(font
					(size 1.27 1.27)
					(thickness 0.15)
				)
			)
		)
		(property "Author" "Antmicro"
			(at 0 0 0)
			(layer "B.Fab")
			(hide yes)
			(effects
				(font
					(size 1 1)
					(thickness 0.15)
				)
				(justify mirror)
			)
		)
		(property "License" "Apache-2.0"
			(at 0 0 0)
			(layer "B.Fab")
			(hide yes)
			(effects
				(font
					(size 1 1)
					(thickness 0.15)
				)
				(justify mirror)
			)
		)
		(property "MPN" "CR0402-FX-1001GLF"
			(at 0 0 0)
			(layer "B.Fab")
			(hide yes)
			(effects
				(font
					(size 1 1)
					(thickness 0.15)
				)
				(justify mirror)
			)
		)
		(property "Manufacturer" "Bourns"
			(at 0 0 0)
			(layer "B.Fab")
			(hide yes)
			(effects
				(font
					(size 1 1)
					(thickness 0.15)
				)
				(justify mirror)
			)
		)
		(property "Tolerance" "1%"
			(at 0 0 0)
			(layer "B.Fab")
			(hide yes)
			(effects
				(font
					(size 1 1)
					(thickness 0.15)
				)
				(justify mirror)
			)
		)
		(property "Val" "1k"
			(at 0 0 0)
			(layer "B.Fab")
			(hide yes)
			(effects
				(font
					(size 1 1)
					(thickness 0.15)
				)
				(justify mirror)
			)
		)
		(sheetname "User GPIO + LED + button + DIP switch")
		(sheetfile "user-gpio.kicad_sch")
		(attr smd)
		(fp_rect
			(start -0.925 0.47)
			(end 0.925 -0.47)
			(stroke
				(width 0.05)
				(type default)
			)
			(fill no)
			(layer "B.CrtYd")
		)
		(fp_rect
			(start -0.5 0.25)
			(end 0.5 -0.25)
			(stroke
				(width 0.15)
				(type solid)
			)
			(fill no)
			(layer "B.Fab")
		)
		(pad "1" smd roundrect
			(at -0.48 0)
			(size 0.59 0.64)
			(layers "B.Cu" "B.Mask" "B.Paste")
			(roundrect_rratio 0.25)
			(net 24 "+3V3")
			(pintype "passive")
		)
		(pad "2" smd roundrect
			(at 0.48 0)
			(size 0.59 0.64)
			(layers "B.Cu" "B.Mask" "B.Paste")
			(roundrect_rratio 0.25)
			(net 781 "Net-(D21-A)")
			(pintype "passive")
		)
	)
	(footprint "antmicro-footprints:R_0402_1005Metric"
		(layer "B.Cu")
		(at 218.099999 77.899999 90)
		(descr "Resistor SMD 0402")
		(tags "resistor SMD 0402")
		(property "Reference" "R114"
			(at 3.599999 0.400001 270)
			(layer "B.SilkS")
			(effects
				(font
					(size 0.7 0.7)
					(thickness 0.15)
				)
				(justify left bottom mirror)
			)
		)
		(property "Value" "R_100R_0402"
			(at 0 -1.4 270)
			(layer "B.Fab")
			(effects
				(font
					(size 0.7 0.7)
					(thickness 0.15)
				)
				(justify left bottom mirror)
			)
		)
		(property "Description" "SMD Chip Resistor, 100 ohm, ± 1%, 62.5 mW, 0402 [1005 Metric], Thick Film, General Purpose"
			(at 0 0 90)
			(layer "F.Fab")
			(hide yes)
			(effects
				(font
					(size 1.27 1.27)
					(thickness 0.15)
				)
			)
		)
		(property "Author" "Antmicro"
			(at 295.999998 -140.2 0)
			(layer "B.Fab")
			(hide yes)
			(effects
				(font
					(size 1 1)
					(thickness 0.15)
				)
				(justify mirror)
			)
		)
		(property "License" "Apache-2.0"
			(at 295.999998 -140.2 0)
			(layer "B.Fab")
			(hide yes)
			(effects
				(font
					(size 1 1)
					(thickness 0.15)
				)
				(justify mirror)
			)
		)
		(property "MPN" "CR0402-FX-1000GLF"
			(at 295.999998 -140.2 0)
			(layer "B.Fab")
			(hide yes)
			(effects
				(font
					(size 1 1)
					(thickness 0.15)
				)
				(justify mirror)
			)
		)
		(property "Manufacturer" "Bourns"
			(at 295.999998 -140.2 0)
			(layer "B.Fab")
			(hide yes)
			(effects
				(font
					(size 1 1)
					(thickness 0.15)
				)
				(justify mirror)
			)
		)
		(property "Tolerance" "1%"
			(at 295.999998 -140.2 0)
			(layer "B.Fab")
			(hide yes)
			(effects
				(font
					(size 1 1)
					(thickness 0.15)
				)
				(justify mirror)
			)
		)
		(property "Val" "100R"
			(at 295.999998 -140.2 0)
			(layer "B.Fab")
			(hide yes)
			(effects
				(font
					(size 1 1)
					(thickness 0.15)
				)
				(justify mirror)
			)
		)
		(sheetname "User GPIO + LED + button + DIP switch")
		(sheetfile "user-gpio.kicad_sch")
		(attr smd)
		(fp_rect
			(start -0.925 0.47)
			(end 0.925 -0.47)
			(stroke
				(width 0.05)
				(type default)
			)
			(fill no)
			(layer "B.CrtYd")
		)
		(fp_rect
			(start -0.5 0.25)
			(end 0.5 -0.25)
			(stroke
				(width 0.15)
				(type solid)
			)
			(fill no)
			(layer "B.Fab")
		)
		(pad "1" smd roundrect
			(at -0.48 0 90)
			(size 0.59 0.64)
			(layers "B.Cu" "B.Mask" "B.Paste")
			(roundrect_rratio 0.25)
			(net 804 "/User GPIO + LED + button + DIP switch/PMOD_A_9")
			(pintype "passive")
		)
		(pad "2" smd roundrect
			(at 0.48 0 90)
			(size 0.59 0.64)
			(layers "B.Cu" "B.Mask" "B.Paste")
			(roundrect_rratio 0.25)
			(net 438 "/FPGA Bank 12 & 13/PMOD_A.IO9")
			(pintype "passive")
		)
	)
)
